(kicad_pcb
	(version 20260206)
	(generator "pcbnew")
	(generator_version "10.0")
	(general
		(thickness 1.6)
		(legacy_teardrops no)
	)
	(paper "A4")
	(title_block
		(title "baseboard — 13948-1b.1110WZS1818.brd")
		(comment 1 "Honey Badger (Wiwynn) / footprints 449-457 of 2523")
	)
	(layers
		(0 "F.Cu" signal "TOP")
		(4 "In1.Cu" signal "L2GND")
		(6 "In2.Cu" signal "L3")
		(8 "In3.Cu" signal "L4VCC")
		(10 "In4.Cu" signal "L5VCC")
		(12 "In5.Cu" signal "L6")
		(14 "In6.Cu" signal "L7GND")
		(2 "B.Cu" signal "BOTTOM")
		(9 "F.Adhes" user "F.Adhesive")
		(11 "B.Adhes" user "B.Adhesive")
		(13 "F.Paste" user "Package Geometry/Pastemask Top")
		(15 "B.Paste" user "Package Geometry/Pastemask Bottom")
		(5 "F.SilkS" user "Ref Des/Silkscreen Top")
		(7 "B.SilkS" user "Ref Des/Silkscreen Bottom")
		(1 "F.Mask" user "Board Geometry/Soldermask Top")
		(3 "B.Mask" user "Board Geometry/Soldermask Bottom")
		(17 "Dwgs.User" user "User.Drawings")
		(19 "Cmts.User" user "User.Comments")
		(21 "Eco1.User" user "User.Eco1")
		(23 "Eco2.User" user "User.Eco2")
		(25 "Edge.Cuts" user "Board Geometry/Outline")
		(27 "Margin" user)
		(31 "F.CrtYd" user "Package Geometry/Place Bound Top")
		(29 "B.CrtYd" user "Package Geometry/Place Bound Bottom")
		(35 "F.Fab" user "Ref Des/Assembly Top")
		(33 "B.Fab" user "Ref Des/Assembly Bottom")
	)
	(footprint ""
		(layer "F.Cu")
		(at 274.193 -163.576 90)
		(property "Reference" "R671"
			(at 0 0 90)
			(layer "F.SilkS")
			(hide yes)
			(effects
				(font
					(size 1.27 1.27)
				)
			)
		)
		(property "Value" "0R2J-2-GP"
			(at 0.064008 -3.993896 90)
			(unlocked yes)
			(layer "F.Fab")
			(hide yes)
			(effects
				(font
					(size 1.016 1.016)
					(thickness 0.1524)
				)
			)
		)
		(property "Device Type" "R402H16"
			(at 0.064008 -5.517896 90)
			(unlocked yes)
			(layer "F.Fab")
			(hide yes)
			(effects
				(font
					(size 1.016 1.016)
					(thickness 0.1524)
				)
			)
		)
		(duplicate_pad_numbers_are_jumpers no)
		(fp_line
			(start 0.508 -0.9398)
			(end -0.508 -0.9398)
			(stroke
				(width 0.1524)
				(type default)
			)
			(layer "F.SilkS")
		)
		(fp_line
			(start -0.508 -0.9398)
			(end -0.508 0.9398)
			(stroke
				(width 0.1524)
				(type default)
			)
			(layer "F.SilkS")
		)
		(fp_rect
			(start -0.508 0.9398)
			(end 0.508 -0.9398)
			(stroke
				(width 0)
				(type default)
			)
			(fill no)
			(layer "F.CrtYd")
		)
		(fp_rect
			(start -0.508 0.9398)
			(end 0.508 -0.9398)
			(stroke
				(width 0)
				(type default)
			)
			(fill no)
			(layer "F.Fab")
		)
		(pad "1" smd custom
			(at 0 -0.4445 90)
			(size 0.1397 0.1397)
			(layers "F.Cu" "F.Mask" "F.Paste")
			(net "USB_OCS_N1")
			(options
				(clearance outline)
				(anchor circle)
			)
			(primitives
				(gr_poly
					(pts
						(arc
							(start -0.1778 -0.2794)
							(mid -0.249642 -0.249642)
							(end -0.2794 -0.1778)
						)
						(arc
							(start -0.2794 0.1778)
							(mid -0.249642 0.249642)
							(end -0.1778 0.2794)
						)
						(arc
							(start 0.1778 0.2794)
							(mid 0.249642 0.249642)
							(end 0.2794 0.1778)
						)
						(arc
							(start 0.2794 -0.1778)
							(mid 0.249642 -0.249642)
							(end 0.1778 -0.2794)
						)
					)
					(width 0)
					(fill yes)
				)
			)
		)
		(pad "2" smd custom
			(at 0 0.4445 90)
			(size 0.1397 0.1397)
			(layers "F.Cu" "F.Mask" "F.Paste")
			(net "TP_BMC_GPIOI0")
			(options
				(clearance outline)
				(anchor circle)
			)
			(primitives
				(gr_poly
					(pts
						(arc
							(start -0.1778 -0.2794)
							(mid -0.249642 -0.249642)
							(end -0.2794 -0.1778)
						)
						(arc
							(start -0.2794 0.1778)
							(mid -0.249642 0.249642)
							(end -0.1778 0.2794)
						)
						(arc
							(start 0.1778 0.2794)
							(mid 0.249642 0.249642)
							(end 0.2794 0.1778)
						)
						(arc
							(start 0.2794 -0.1778)
							(mid 0.249642 -0.249642)
							(end 0.1778 -0.2794)
						)
					)
					(width 0)
					(fill yes)
				)
			)
		)
	)
	(footprint ""
		(layer "F.Cu")
		(at 193.167 -16.129 -90)
		(property "Reference" "R5307"
			(at 0 0 270)
			(layer "F.SilkS")
			(hide yes)
			(effects
				(font
					(size 1.27 1.27)
				)
			)
		)
		(property "Value" "0R2J-2-GP"
			(at 0.064008 -3.993896 270)
			(unlocked yes)
			(layer "F.Fab")
			(hide yes)
			(effects
				(font
					(size 1.016 1.016)
					(thickness 0.1524)
				)
			)
		)
		(property "Device Type" "R402H16"
			(at 0.064008 -5.517896 270)
			(unlocked yes)
			(layer "F.Fab")
			(hide yes)
			(effects
				(font
					(size 1.016 1.016)
					(thickness 0.1524)
				)
			)
		)
		(duplicate_pad_numbers_are_jumpers no)
		(fp_line
			(start -0.508 -0.9398)
			(end -0.508 0.9398)
			(stroke
				(width 0.1524)
				(type default)
			)
			(layer "F.SilkS")
		)
		(fp_line
			(start 0.508 -0.9398)
			(end -0.508 -0.9398)
			(stroke
				(width 0.1524)
				(type default)
			)
			(layer "F.SilkS")
		)
		(fp_rect
			(start -0.508 0.9398)
			(end 0.508 -0.9398)
			(stroke
				(width 0)
				(type default)
			)
			(fill no)
			(layer "F.CrtYd")
		)
		(fp_rect
			(start -0.508 0.9398)
			(end 0.508 -0.9398)
			(stroke
				(width 0)
				(type default)
			)
			(fill no)
			(layer "F.Fab")
		)
		(pad "1" smd custom
			(at 0 -0.4445 270)
			(size 0.1397 0.1397)
			(layers "F.Cu" "F.Mask" "F.Paste")
			(net "BMC_I2C_SCL_10")
			(options
				(clearance outline)
				(anchor circle)
			)
			(primitives
				(gr_poly
					(pts
						(arc
							(start -0.1778 -0.2794)
							(mid -0.249642 -0.249642)
							(end -0.2794 -0.1778)
						)
						(arc
							(start -0.2794 0.1778)
							(mid -0.249642 0.249642)
							(end -0.1778 0.2794)
						)
						(arc
							(start 0.1778 0.2794)
							(mid 0.249642 0.249642)
							(end 0.2794 0.1778)
						)
						(arc
							(start 0.2794 -0.1778)
							(mid 0.249642 -0.249642)
							(end 0.1778 -0.2794)
						)
					)
					(width 0)
					(fill yes)
				)
			)
		)
		(pad "2" smd custom
			(at 0 0.4445 270)
			(size 0.1397 0.1397)
			(layers "F.Cu" "F.Mask" "F.Paste")
			(net "TEMP_1_SCL")
			(options
				(clearance outline)
				(anchor circle)
			)
			(primitives
				(gr_poly
					(pts
						(arc
							(start -0.1778 -0.2794)
							(mid -0.249642 -0.249642)
							(end -0.2794 -0.1778)
						)
						(arc
							(start -0.2794 0.1778)
							(mid -0.249642 0.249642)
							(end -0.1778 0.2794)
						)
						(arc
							(start 0.1778 0.2794)
							(mid 0.249642 0.249642)
							(end 0.2794 0.1778)
						)
						(arc
							(start 0.2794 -0.1778)
							(mid 0.249642 -0.249642)
							(end 0.1778 -0.2794)
						)
					)
					(width 0)
					(fill yes)
				)
			)
		)
	)
	(footprint ""
		(layer "F.Cu")
		(at 283.074872 -64.080136)
		(property "Reference" "C268"
			(at 0 0 0)
			(layer "F.SilkS")
			(hide yes)
			(effects
				(font
					(size 1.27 1.27)
				)
			)
		)
		(property "Value" "SC22U6D3V5MX-2GP"
			(at -0.0762 -6.1214 0)
			(unlocked yes)
			(layer "F.Fab")
			(hide yes)
			(effects
				(font
					(size 1.016 1.016)
					(thickness 0.1524)
				)
			)
		)
		(property "Device Type" "C805H58"
			(at -0.0762 -8.1534 0)
			(unlocked yes)
			(layer "F.Fab")
			(hide yes)
			(effects
				(font
					(size 1.016 1.016)
					(thickness 0.1524)
				)
			)
		)
		(duplicate_pad_numbers_are_jumpers no)
		(fp_line
			(start 0.635 0)
			(end -0.635 0)
			(stroke
				(width 0.508)
				(type default)
			)
			(layer "F.SilkS")
		)
		(fp_rect
			(start -0.9652 1.778)
			(end 0.9652 -1.778)
			(stroke
				(width 0)
				(type default)
			)
			(fill no)
			(layer "F.CrtYd")
		)
		(fp_poly
			(pts
				(xy -0.9652 -1.778) (xy 0.9652 -1.778) (xy 0.9652 1.778) (xy -0.9652 1.778)
			)
			(stroke
				(width 0)
				(type default)
			)
			(fill no)
			(layer "F.Fab")
		)
		(pad "1" smd rect
			(at 0 -0.9652)
			(size 1.397 1.143)
			(layers "F.Cu" "F.Mask" "F.Paste")
			(net "PRSNT_EN_HPIC")
		)
		(pad "2" smd rect
			(at 0 0.9652)
			(size 1.397 1.143)
			(layers "F.Cu" "F.Mask" "F.Paste")
			(net "GND")
		)
	)
	(footprint ""
		(layer "F.Cu")
		(at 288.987992 -191.842136 180)
		(property "Reference" "C184"
			(at 0 0 180)
			(layer "F.SilkS")
			(hide yes)
			(effects
				(font
					(size 1.27 1.27)
				)
			)
		)
		(property "Value" "SCD1U16V2KX-3GP"
			(at 1.1811 -2.7051 180)
			(unlocked yes)
			(layer "F.Fab")
			(hide yes)
			(effects
				(font
					(size 1.016 1.016)
					(thickness 0.1524)
				)
			)
		)
		(property "Device Type" "C402H22"
			(at 1.1811 -4.2291 180)
			(unlocked yes)
			(layer "F.Fab")
			(hide yes)
			(effects
				(font
					(size 1.016 1.016)
					(thickness 0.1524)
				)
			)
		)
		(duplicate_pad_numbers_are_jumpers no)
		(fp_rect
			(start -0.4318 0.9525)
			(end 0.4318 -0.9525)
			(stroke
				(width 0)
				(type default)
			)
			(fill no)
			(layer "F.CrtYd")
		)
		(fp_rect
			(start -0.4318 0.9525)
			(end 0.4318 -0.9525)
			(stroke
				(width 0)
				(type default)
			)
			(fill no)
			(layer "F.Fab")
		)
		(pad "1" smd custom
			(at 0 -0.4445 180)
			(size 0.1524 0.1524)
			(layers "F.Cu" "F.Mask" "F.Paste")
			(net "GND")
			(options
				(clearance outline)
				(anchor circle)
			)
			(primitives
				(gr_poly
					(pts
						(arc
							(start 0.3048 -0.2032)
							(mid 0.275042 -0.275042)
							(end 0.2032 -0.3048)
						)
						(arc
							(start -0.2032 -0.3048)
							(mid -0.275042 -0.275042)
							(end -0.3048 -0.2032)
						)
						(arc
							(start -0.3048 0.2032)
							(mid -0.275042 0.275042)
							(end -0.2032 0.3048)
						)
						(arc
							(start 0.2032 0.3048)
							(mid 0.275042 0.275042)
							(end 0.3048 0.2032)
						)
					)
					(width 0)
					(fill yes)
				)
			)
		)
		(pad "2" smd custom
			(at 0 0.4445 180)
			(size 0.1524 0.1524)
			(layers "F.Cu" "F.Mask" "F.Paste")
			(net "DDR_VREF")
			(options
				(clearance outline)
				(anchor circle)
			)
			(primitives
				(gr_poly
					(pts
						(arc
							(start 0.3048 -0.2032)
							(mid 0.275042 -0.275042)
							(end 0.2032 -0.3048)
						)
						(arc
							(start -0.2032 -0.3048)
							(mid -0.275042 -0.275042)
							(end -0.3048 -0.2032)
						)
						(arc
							(start -0.3048 0.2032)
							(mid -0.275042 0.275042)
							(end -0.2032 0.3048)
						)
						(arc
							(start 0.2032 0.3048)
							(mid 0.275042 0.275042)
							(end 0.3048 0.2032)
						)
					)
					(width 0)
					(fill yes)
				)
			)
		)
	)
	(footprint ""
		(layer "F.Cu")
		(at 306.578 -181.737)
		(property "Reference" "TP110"
			(at 0 0 0)
			(layer "F.SilkS")
			(hide yes)
			(effects
				(font
					(size 1.27 1.27)
				)
			)
		)
		(property "Value" "TPAD28"
			(at 0.0127 -1.8034 0)
			(unlocked yes)
			(layer "F.Fab")
			(hide yes)
			(effects
				(font
					(size 1.016 1.016)
					(thickness 0.1524)
				)
			)
		)
		(property "Device Type" "TPAD28"
			(at 0.0127 -3.3274 0)
			(unlocked yes)
			(layer "F.Fab")
			(hide yes)
			(effects
				(font
					(size 1.016 1.016)
					(thickness 0.1524)
				)
			)
		)
		(duplicate_pad_numbers_are_jumpers no)
		(fp_poly
			(pts
				(arc
					(start 0.3556 0)
					(mid -0.3556 0)
					(end 0.3556 0)
				)
			)
			(stroke
				(width 0)
				(type default)
			)
			(fill no)
			(layer "F.CrtYd")
		)
		(fp_poly
			(pts
				(arc
					(start 0.6096 0)
					(mid -0.6096 0)
					(end 0.6096 0)
				)
			)
			(stroke
				(width 0)
				(type default)
			)
			(fill no)
			(layer "F.Fab")
		)
		(pad "1" smd circle
			(at 0 0)
			(size 0.7112 0.7112)
			(layers "F.Cu" "F.Mask" "F.Paste")
			(net "TP_BMC_GPIOL6")
		)
	)
	(footprint ""
		(layer "F.Cu")
		(at 184.903872 -196.083936 180)
		(property "Reference" "C247"
			(at 0 0 180)
			(layer "F.SilkS")
			(hide yes)
			(effects
				(font
					(size 1.27 1.27)
				)
			)
		)
		(property "Value" "SC220P50V3JN-GP"
			(at 0 -2.8194 180)
			(unlocked yes)
			(layer "F.Fab")
			(hide yes)
			(effects
				(font
					(size 1.016 1.016)
					(thickness 0.1524)
				)
			)
		)
		(property "Device Type" "C603H36"
			(at 0 -4.3434 180)
			(unlocked yes)
			(layer "F.Fab")
			(hide yes)
			(effects
				(font
					(size 1.016 1.016)
					(thickness 0.1524)
				)
			)
		)
		(duplicate_pad_numbers_are_jumpers no)
		(fp_line
			(start 0.508 0)
			(end -0.508 0)
			(stroke
				(width 0.2032)
				(type default)
			)
			(layer "F.SilkS")
		)
		(fp_rect
			(start -0.5842 1.3335)
			(end 0.5842 -1.3335)
			(stroke
				(width 0)
				(type default)
			)
			(fill no)
			(layer "F.CrtYd")
		)
		(fp_rect
			(start -0.5842 1.3335)
			(end 0.5842 -1.3335)
			(stroke
				(width 0)
				(type default)
			)
			(fill no)
			(layer "F.Fab")
		)
		(pad "1" smd custom
			(at 0 -0.762 180)
			(size 0.2159 0.2159)
			(layers "F.Cu" "F.Mask" "F.Paste")
			(net "BMC_I2C_C_SDA")
			(options
				(clearance outline)
				(anchor circle)
			)
			(primitives
				(gr_poly
					(pts
						(arc
							(start -0.3302 -0.4318)
							(mid -0.402042 -0.402042)
							(end -0.4318 -0.3302)
						)
						(arc
							(start -0.4318 0.3302)
							(mid -0.402042 0.402042)
							(end -0.3302 0.4318)
						)
						(arc
							(start 0.3302 0.4318)
							(mid 0.402042 0.402042)
							(end 0.4318 0.3302)
						)
						(arc
							(start 0.4318 -0.3302)
							(mid 0.402042 -0.402042)
							(end 0.3302 -0.4318)
						)
					)
					(width 0)
					(fill yes)
				)
			)
		)
		(pad "2" smd custom
			(at 0 0.762 180)
			(size 0.2159 0.2159)
			(layers "F.Cu" "F.Mask" "F.Paste")
			(net "GND")
			(options
				(clearance outline)
				(anchor circle)
			)
			(primitives
				(gr_poly
					(pts
						(arc
							(start -0.3302 -0.4318)
							(mid -0.402042 -0.402042)
							(end -0.4318 -0.3302)
						)
						(arc
							(start -0.4318 0.3302)
							(mid -0.402042 0.402042)
							(end -0.3302 0.4318)
						)
						(arc
							(start 0.3302 0.4318)
							(mid 0.402042 0.402042)
							(end 0.4318 0.3302)
						)
						(arc
							(start 0.4318 -0.3302)
							(mid 0.402042 -0.402042)
							(end 0.3302 -0.4318)
						)
					)
					(width 0)
					(fill yes)
				)
			)
		)
	)
	(footprint ""
		(layer "F.Cu")
		(at 270.959072 -52.126896 180)
		(property "Reference" "PU9"
			(at 0 0 180)
			(layer "F.SilkS")
			(hide yes)
			(effects
				(font
					(size 1.27 1.27)
				)
			)
		)
		(property "Value" "2N7002DW-7F-GP"
			(at -2.3622 -8.2042 180)
			(unlocked yes)
			(layer "F.Fab")
			(hide yes)
			(effects
				(font
					(size 1.016 1.016)
					(thickness 0.1524)
				)
			)
		)
		(property "Device Type" "SOT-363H44"
			(at -2.3622 -10.1092 180)
			(unlocked yes)
			(layer "F.Fab")
			(hide yes)
			(effects
				(font
					(size 1.016 1.016)
					(thickness 0.1524)
				)
			)
		)
		(duplicate_pad_numbers_are_jumpers no)
		(fp_line
			(start 1.4478 1.7018)
			(end 1.4478 -1.7018)
			(stroke
				(width 0.1524)
				(type default)
			)
			(layer "F.SilkS")
		)
		(fp_line
			(start 1.4478 -1.7018)
			(end -1.4478 -1.7018)
			(stroke
				(width 0.1524)
				(type default)
			)
			(layer "F.SilkS")
		)
		(fp_line
			(start -1.27 1.524)
			(end -1.27 0.6604)
			(stroke
				(width 0.4826)
				(type default)
			)
			(layer "F.SilkS")
		)
		(fp_line
			(start -1.4478 1.7018)
			(end 1.4478 1.7018)
			(stroke
				(width 0.1524)
				(type default)
			)
			(layer "F.SilkS")
		)
		(fp_line
			(start -1.4478 -1.7018)
			(end -1.4478 1.7018)
			(stroke
				(width 0.1524)
				(type default)
			)
			(layer "F.SilkS")
		)
		(fp_poly
			(pts
				(xy -1.524 -1.778) (xy 1.524 -1.778) (xy 1.524 1.778) (xy -1.524 1.778)
			)
			(stroke
				(width 0)
				(type default)
			)
			(fill no)
			(layer "F.CrtYd")
		)
		(fp_poly
			(pts
				(xy -1.524 -1.778) (xy 1.524 -1.778) (xy 1.524 1.778) (xy -1.524 1.778)
			)
			(stroke
				(width 0)
				(type default)
			)
			(fill no)
			(layer "F.Fab")
		)
		(pad "1" smd rect
			(at -0.65024 0.9398 180)
			(size 0.4064 1.016)
			(layers "F.Cu" "F.Mask" "F.Paste")
			(net "GND")
		)
		(pad "2" smd rect
			(at 0 0.9398 180)
			(size 0.4064 1.016)
			(layers "F.Cu" "F.Mask" "F.Paste")
			(net "P3V3_EN_B")
		)
		(pad "3" smd rect
			(at 0.65024 0.9398 180)
			(size 0.4064 1.016)
			(layers "F.Cu" "F.Mask" "F.Paste")
			(net "P3V3_EN_LV")
		)
		(pad "4" smd rect
			(at 0.65024 -0.9398 180)
			(size 0.4064 1.016)
			(layers "F.Cu" "F.Mask" "F.Paste")
			(net "GND")
		)
		(pad "5" smd rect
			(at 0 -0.9398 180)
			(size 0.4064 1.016)
			(layers "F.Cu" "F.Mask" "F.Paste")
			(net "P3V3_S_LV")
		)
		(pad "6" smd rect
			(at -0.65024 -0.9398 180)
			(size 0.4064 1.016)
			(layers "F.Cu" "F.Mask" "F.Paste")
			(net "P3V3_S_LV")
		)
	)
	(footprint ""
		(layer "F.Cu")
		(at 91.929966 -61.468)
		(property "Reference" "STP36"
			(at 0 0 0)
			(layer "F.SilkS")
			(hide yes)
			(effects
				(font
					(size 1.27 1.27)
				)
			)
		)
		(property "Value" "TPAD28"
			(at 0.0127 -1.8034 0)
			(unlocked yes)
			(layer "F.Fab")
			(hide yes)
			(effects
				(font
					(size 1.016 1.016)
					(thickness 0.1524)
				)
			)
		)
		(property "Device Type" "TPAD28"
			(at 0.0127 -3.3274 0)
			(unlocked yes)
			(layer "F.Fab")
			(hide yes)
			(effects
				(font
					(size 1.016 1.016)
					(thickness 0.1524)
				)
			)
		)
		(duplicate_pad_numbers_are_jumpers no)
		(fp_poly
			(pts
				(arc
					(start 0.3556 0)
					(mid -0.3556 0)
					(end 0.3556 0)
				)
			)
			(stroke
				(width 0)
				(type default)
			)
			(fill no)
			(layer "F.CrtYd")
		)
		(fp_poly
			(pts
				(arc
					(start 0.6096 0)
					(mid -0.6096 0)
					(end 0.6096 0)
				)
			)
			(stroke
				(width 0)
				(type default)
			)
			(fill no)
			(layer "F.Fab")
		)
		(pad "1" smd circle
			(at 0 0)
			(size 0.7112 0.7112)
			(layers "F.Cu" "F.Mask" "F.Paste")
			(net "ICE1_TMS")
		)
	)
	(footprint ""
		(layer "F.Cu")
		(at 333.912718 -156.695648 90)
		(property "Reference" "R248"
			(at 0 0 90)
			(layer "F.SilkS")
			(hide yes)
			(effects
				(font
					(size 1.27 1.27)
				)
			)
		)
		(property "Value" "4K7R2F-GP"
			(at 0.064008 -3.993896 90)
			(unlocked yes)
			(layer "F.Fab")
			(hide yes)
			(effects
				(font
					(size 1.016 1.016)
					(thickness 0.1524)
				)
			)
		)
		(property "Device Type" "R402H16"
			(at 0.064008 -5.517896 90)
			(unlocked yes)
			(layer "F.Fab")
			(hide yes)
			(effects
				(font
					(size 1.016 1.016)
					(thickness 0.1524)
				)
			)
		)
		(duplicate_pad_numbers_are_jumpers no)
		(fp_line
			(start 0.508 -0.9398)
			(end -0.508 -0.9398)
			(stroke
				(width 0.1524)
				(type default)
			)
			(layer "F.SilkS")
		)
		(fp_line
			(start -0.508 -0.9398)
			(end -0.508 0.9398)
			(stroke
				(width 0.1524)
				(type default)
			)
			(layer "F.SilkS")
		)
		(fp_rect
			(start -0.508 0.9398)
			(end 0.508 -0.9398)
			(stroke
				(width 0)
				(type default)
			)
			(fill no)
			(layer "F.CrtYd")
		)
		(fp_rect
			(start -0.508 0.9398)
			(end 0.508 -0.9398)
			(stroke
				(width 0)
				(type default)
			)
			(fill no)
			(layer "F.Fab")
		)
		(pad "1" smd custom
			(at 0 -0.4445 90)
			(size 0.1397 0.1397)
			(layers "F.Cu" "F.Mask" "F.Paste")
			(net "P3V3_STBY")
			(options
				(clearance outline)
				(anchor circle)
			)
			(primitives
				(gr_poly
					(pts
						(arc
							(start -0.1778 -0.2794)
							(mid -0.249642 -0.249642)
							(end -0.2794 -0.1778)
						)
						(arc
							(start -0.2794 0.1778)
							(mid -0.249642 0.249642)
							(end -0.1778 0.2794)
						)
						(arc
							(start 0.1778 0.2794)
							(mid 0.249642 0.249642)
							(end 0.2794 0.1778)
						)
						(arc
							(start 0.2794 -0.1778)
							(mid 0.249642 -0.249642)
							(end 0.1778 -0.2794)
						)
					)
					(width 0)
					(fill yes)
				)
			)
		)
		(pad "2" smd custom
			(at 0 0.4445 90)
			(size 0.1397 0.1397)
			(layers "F.Cu" "F.Mask" "F.Paste")
			(net "USB_EN_4")
			(options
				(clearance outline)
				(anchor circle)
			)
			(primitives
				(gr_poly
					(pts
						(arc
							(start -0.1778 -0.2794)
							(mid -0.249642 -0.249642)
							(end -0.2794 -0.1778)
						)
						(arc
							(start -0.2794 0.1778)
							(mid -0.249642 0.249642)
							(end -0.1778 0.2794)
						)
						(arc
							(start 0.1778 0.2794)
							(mid 0.249642 0.249642)
							(end 0.2794 0.1778)
						)
						(arc
							(start 0.2794 -0.1778)
							(mid 0.249642 -0.249642)
							(end 0.1778 -0.2794)
						)
					)
					(width 0)
					(fill yes)
				)
			)
		)
	)
)
